# TIMECARD (Time Appliance Project (Time Card)) — schematic netlist excerpt (pin names and nets, part order shuffled) for the footprints in the layout excerpt that follows; sources: Cadence DE-HDL packaged netlist, KiCad conversion of R4006-B0001-02_R01.brd

U12  TPS2051BDBVT_SOT23_5  pkg SOT23_5  page 21
  \out\  = XP5R0V_MAC_USB
  GND  = SG
  \oc*\  = UNNAMED_527_RESISTOR_I206_1
  EN  = USB_PWR_EN
  \in\  = XP5R0V_MAC

(kicad_pcb
	(version 20260206)
	(generator "pcbnew")
	(generator_version "10.0")
	(general
		(thickness 1.6)
		(legacy_teardrops no)
	)
	(paper "A4")
	(title_block
		(title "timecard-production-celestica-r4006 — R4006-B0001-02_R01.brd")
		(comment 1 "Time Appliance Project (Time Card) / footprint 898 of 1113 (U12), pads 1-5 of 5")
	)
	(layers
		(0 "F.Cu" signal "TOP")
		(4 "In1.Cu" signal "L02_GND1")
		(6 "In2.Cu" signal "L03_SIG1")
		(8 "In3.Cu" signal "L04_GND2")
		(10 "In4.Cu" signal "L05_VCC1")
		(12 "In5.Cu" signal "L06_VCC2")
		(14 "In6.Cu" signal "L07_GND3")
		(16 "In7.Cu" signal "L08_SIG2")
		(18 "In8.Cu" signal "L09_GND4")
		(2 "B.Cu" signal "BOTTOM")
		(9 "F.Adhes" user "F.Adhesive")
		(11 "B.Adhes" user "B.Adhesive")
		(13 "F.Paste" user "Package Geometry/Pastemask Top")
		(15 "B.Paste" user "Package Geometry/Pastemask Bottom")
		(5 "F.SilkS" user "Ref Des/Silkscreen Top")
		(7 "B.SilkS" user "Ref Des/Silkscreen Bottom")
		(1 "F.Mask" user "Board Geometry/Soldermask Top")
		(3 "B.Mask" user "Board Geometry/Soldermask Bottom")
		(17 "Dwgs.User" user "User.Drawings")
		(19 "Cmts.User" user "User.Comments")
		(21 "Eco1.User" user "User.Eco1")
		(23 "Eco2.User" user "User.Eco2")
		(25 "Edge.Cuts" user "Board Geometry/Outline")
		(27 "Margin" user)
		(31 "F.CrtYd" user "Package Geometry/Place Bound Top")
		(29 "B.CrtYd" user "Package Geometry/Place Bound Bottom")
		(35 "F.Fab" user "Ref Des/Assembly Top")
		(33 "B.Fab" user "Ref Des/Assembly Bottom")
	)
	(footprint ""
		(layer "B.Cu")
		(at 68.326 -57.15 -90)
		(property "Reference" "U12"
			(at 3.97637 -1.143 0)
			(unlocked yes)
			(layer "B.SilkS")
			(effects
				(font
					(size 0.7874 0.5842)
					(thickness 0.1524)
				)
				(justify mirror)
			)
		)
		(property "Value" ""
			(at 0 0 90)
			(layer "B.Fab")
			(effects
				(font
					(size 1.27 1.27)
				)
				(justify mirror)
			)
		)
		(property "Device Type" "TPS2051BDBVT_SOT23_5-G220-1033A"
			(at -0.0508 2.549906 270)
			(unlocked yes)
			(layer "B.Fab")
			(hide yes)
			(effects
				(font
					(size 0.7874 0.5842)
					(thickness 0.1524)
				)
				(justify mirror)
			)
		)
		(property "User Part Number" "PARTNUM*"
			(at -0.0508 3.515106 270)
			(unlocked yes)
			(layer "Cmts.User")
			(hide yes)
			(effects
				(font
					(size 0.7874 0.5842)
					(thickness 0.1524)
				)
				(justify mirror)
			)
		)
		(duplicate_pad_numbers_are_jumpers no)
		(pad "1" smd rect
			(at 1.4351 -0.94996)
			(size 0.508 1.1938)
			(layers "B.Cu" "B.Mask" "B.Paste")
			(net "XP5R0V_MAC_USB")
		)
		(pad "2" smd rect
			(at 1.4351 0)
			(size 0.508 1.1938)
			(layers "B.Cu" "B.Mask" "B.Paste")
			(net "SG")
		)
		(pad "3" smd rect
			(at 1.4351 0.94996)
			(size 0.508 1.1938)
			(layers "B.Cu" "B.Mask" "B.Paste")
			(net "UNNAMED_527_RESISTOR_I206_1")
		)
		(pad "4" smd rect
			(at -1.4351 0.94996)
			(size 0.508 1.1938)
			(layers "B.Cu" "B.Mask" "B.Paste")
			(net "USB_PWR_EN")
		)
		(pad "5" smd rect
			(at -1.4351 -0.94996)
			(size 0.508 1.1938)
			(layers "B.Cu" "B.Mask" "B.Paste")
			(net "XP5R0V_MAC")
		)
	)
)
